# T6G (Grand Teton) — schematic netlist excerpt (pin names and nets, part order shuffled) for the footprints in the layout excerpt that follows; sources: Cadence DE-HDL packaged netlist, KiCad conversion of 04192023_DAF0TMB3IC0_F0TG_MB_C_brd_V02_OCP.brd

R3177  Q_RES  0 5% CHIP  pkg 0402LF  page 137 : A = USB2_P10_DN ; B = USB2_CPU0_P10_DN

U272  LM75BD  IC  pkg SO8_1-27_4-9X3-9  page 235
  SDA  = SMB_LM75_2_3V3AUX_SDA_R1
  SCL  = SMB_LM75_2_3V3AUX_SCL_R1
  OS  = FM_LM75_2_ALERT_N
  GND  = GND
  A2  = U272_2_ADD2
  A1  = U272_2_ADD1
  A0  = U272_2_ADD0
  VCC  = P3V3_AUX

(kicad_pcb
	(version 20260206)
	(generator "pcbnew")
	(generator_version "10.0")
	(general
		(thickness 1.6)
		(legacy_teardrops no)
	)
	(paper "A4")
	(title_block
		(title "04192023_DAF0TMB3IC0_F0TG_MB_C_brd_V02_OCP.brd")
		(comment 1 "Grand Teton / footprints 4584-4585 of 8354")
	)
	(layers
		(0 "F.Cu" signal "TOP")
		(4 "In1.Cu" signal "GND")
		(6 "In2.Cu" signal "IN1")
		(8 "In3.Cu" signal "GND1")
		(10 "In4.Cu" signal "IN2")
		(12 "In5.Cu" signal "GND2")
		(14 "In6.Cu" signal "IN3")
		(16 "In7.Cu" signal "GND3")
		(18 "In8.Cu" signal "VCC")
		(20 "In9.Cu" signal "VCC1")
		(22 "In10.Cu" signal "GND4")
		(24 "In11.Cu" signal "IN4")
		(26 "In12.Cu" signal "GND5")
		(28 "In13.Cu" signal "IN5")
		(30 "In14.Cu" signal "GND6")
		(32 "In15.Cu" signal "IN6")
		(34 "In16.Cu" signal "GND7")
		(2 "B.Cu" signal "BOTTOM")
		(9 "F.Adhes" user "F.Adhesive")
		(11 "B.Adhes" user "B.Adhesive")
		(13 "F.Paste" user "Package Geometry/Pastemask Top")
		(15 "B.Paste" user "Package Geometry/Pastemask Bottom")
		(5 "F.SilkS" user "Ref Des/Silkscreen Top")
		(7 "B.SilkS" user "Ref Des/Silkscreen Bottom")
		(1 "F.Mask" user "Board Geometry/Soldermask Top")
		(3 "B.Mask" user "Board Geometry/Soldermask Bottom")
		(17 "Dwgs.User" user "User.Drawings")
		(19 "Cmts.User" user "User.Comments")
		(21 "Eco1.User" user "User.Eco1")
		(23 "Eco2.User" user "User.Eco2")
		(25 "Edge.Cuts" user "Board Geometry/Outline")
		(27 "Margin" user)
		(31 "F.CrtYd" user "Package Geometry/Place Bound Top")
		(29 "B.CrtYd" user "Package Geometry/Place Bound Bottom")
		(35 "F.Fab" user "Ref Des/Assembly Top")
		(33 "B.Fab" user "Ref Des/Assembly Bottom")
	)
	(footprint ""
		(layer "F.Cu")
		(at 12.777216 -15.32128 90)
		(property "Reference" "R3177"
			(at 0 0 90)
			(layer "F.SilkS")
			(hide yes)
			(effects
				(font
					(size 1.27 1.27)
				)
			)
		)
		(property "Value" ""
			(at 0 0 90)
			(layer "F.Fab")
			(effects
				(font
					(size 1.27 1.27)
				)
			)
		)
		(duplicate_pad_numbers_are_jumpers no)
		(fp_line
			(start 0.7874 -0.4064)
			(end 0.7874 0.4064)
			(stroke
				(width 0.1524)
				(type default)
			)
			(layer "F.SilkS")
		)
		(fp_line
			(start -0.7874 -0.4064)
			(end 0.7874 -0.4064)
			(stroke
				(width 0.1524)
				(type default)
			)
			(layer "F.SilkS")
		)
		(fp_line
			(start 0.7874 0.4064)
			(end -0.7874 0.4064)
			(stroke
				(width 0.1524)
				(type default)
			)
			(layer "F.SilkS")
		)
		(fp_line
			(start -0.7874 0.4064)
			(end -0.7874 -0.4064)
			(stroke
				(width 0.1524)
				(type default)
			)
			(layer "F.SilkS")
		)
		(fp_line
			(start -0.12065 -0.305054)
			(end -0.12065 -0.2794)
			(stroke
				(width 0.1)
				(type default)
			)
			(layer "F.Fab")
		)
		(fp_line
			(start -0.67945 -0.305054)
			(end -0.12065 -0.305054)
			(stroke
				(width 0.1)
				(type default)
			)
			(layer "F.Fab")
		)
		(fp_line
			(start 0.67945 -0.3048)
			(end 0.67945 0.3048)
			(stroke
				(width 0.1)
				(type default)
			)
			(layer "F.Fab")
		)
		(fp_line
			(start 0.12065 -0.3048)
			(end 0.67945 -0.3048)
			(stroke
				(width 0.1)
				(type default)
			)
			(layer "F.Fab")
		)
		(fp_line
			(start 0.12065 -0.2794)
			(end 0.12065 -0.3048)
			(stroke
				(width 0.1)
				(type default)
			)
			(layer "F.Fab")
		)
		(fp_line
			(start -0.12065 -0.2794)
			(end 0.12065 -0.2794)
			(stroke
				(width 0.1)
				(type default)
			)
			(layer "F.Fab")
		)
		(fp_line
			(start 0.120396 0.2794)
			(end -0.12065 0.2794)
			(stroke
				(width 0.1)
				(type default)
			)
			(layer "F.Fab")
		)
		(fp_line
			(start -0.12065 0.2794)
			(end -0.12065 0.3048)
			(stroke
				(width 0.1)
				(type default)
			)
			(layer "F.Fab")
		)
		(fp_line
			(start 0.67945 0.3048)
			(end 0.120396 0.3048)
			(stroke
				(width 0.1)
				(type default)
			)
			(layer "F.Fab")
		)
		(fp_line
			(start 0.120396 0.3048)
			(end 0.120396 0.2794)
			(stroke
				(width 0.1)
				(type default)
			)
			(layer "F.Fab")
		)
		(fp_line
			(start -0.12065 0.3048)
			(end -0.67945 0.3048)
			(stroke
				(width 0.1)
				(type default)
			)
			(layer "F.Fab")
		)
		(fp_line
			(start -0.67945 0.3048)
			(end -0.67945 -0.305054)
			(stroke
				(width 0.1)
				(type default)
			)
			(layer "F.Fab")
		)
		(pad "1" smd circle
			(at -0.40005 0 90)
			(size 0 0)
			(layers "F.Cu" "F.Mask" "F.Paste")
			(net "USB2_P10_DN")
		)
		(pad "2" smd circle
			(at 0.40005 0 90)
			(size 0 0)
			(layers "F.Cu" "F.Mask" "F.Paste")
			(net "USB2_CPU0_P10_DN")
		)
	)
	(footprint ""
		(layer "F.Cu")
		(at 99.650296 -417.725098 90)
		(property "Reference" "U272"
			(at 1.712976 -3.64998 90)
			(unlocked yes)
			(layer "F.SilkS")
			(effects
				(font
					(size 0.7874 0.5842)
					(thickness 0.1524)
				)
				(justify left)
			)
		)
		(property "Value" ""
			(at 0 0 90)
			(layer "F.Fab")
			(effects
				(font
					(size 1.27 1.27)
				)
			)
		)
		(duplicate_pad_numbers_are_jumpers no)
		(fp_line
			(start 3.447796 -2.500122)
			(end 1.484122 -2.500122)
			(stroke
				(width 0.1524)
				(type default)
			)
			(layer "F.SilkS")
		)
		(fp_line
			(start 1.484122 -2.500122)
			(end 0 -1.016)
			(stroke
				(width 0.1524)
				(type default)
			)
			(layer "F.SilkS")
		)
		(fp_line
			(start -1.484122 -2.500122)
			(end -3.447796 -2.500122)
			(stroke
				(width 0.1524)
				(type default)
			)
			(layer "F.SilkS")
		)
		(fp_line
			(start -3.447796 -2.500122)
			(end -3.447796 2.500122)
			(stroke
				(width 0.1524)
				(type default)
			)
			(layer "F.SilkS")
		)
		(fp_line
			(start 0 -1.016)
			(end -1.484122 -2.500122)
			(stroke
				(width 0.1524)
				(type default)
			)
			(layer "F.SilkS")
		)
		(fp_line
			(start 3.447796 2.500122)
			(end 3.447796 -2.500122)
			(stroke
				(width 0.1524)
				(type default)
			)
			(layer "F.SilkS")
		)
		(fp_line
			(start -3.447796 2.500122)
			(end 3.447796 2.500122)
			(stroke
				(width 0.1524)
				(type default)
			)
			(layer "F.SilkS")
		)
		(fp_poly
			(pts
				(xy -2.37871 -3.737102) (xy -3.39471 -3.737102) (xy -2.88671 -2.721102)
			)
			(stroke
				(width 0)
				(type default)
			)
			(fill yes)
			(layer "F.SilkS")
		)
		(fp_line
			(start 1.999996 -2.500122)
			(end -1.999996 -2.500122)
			(stroke
				(width 0.1)
				(type default)
			)
			(layer "F.Fab")
		)
		(fp_line
			(start -1.999996 -2.500122)
			(end -1.999996 2.500122)
			(stroke
				(width 0.1)
				(type default)
			)
			(layer "F.Fab")
		)
		(fp_line
			(start 1.999996 2.500122)
			(end 1.999996 -2.500122)
			(stroke
				(width 0.1)
				(type default)
			)
			(layer "F.Fab")
		)
		(fp_line
			(start -1.999996 2.500122)
			(end 1.999996 2.500122)
			(stroke
				(width 0.1)
				(type default)
			)
			(layer "F.Fab")
		)
		(fp_poly
			(pts
				(xy -4.5974 -2.413) (xy -4.5974 -1.397) (xy -3.5814 -1.905)
			)
			(stroke
				(width 0)
				(type default)
			)
			(fill yes)
			(layer "F.Fab")
		)
		(pad "1" smd rect
			(at -2.649982 -1.905)
			(size 0.6096 1.3208)
			(layers "F.Cu" "F.Mask" "F.Paste")
			(net "SMB_LM75_2_3V3AUX_SDA_R1")
		)
		(pad "2" smd rect
			(at -2.649982 -0.635)
			(size 0.6096 1.3208)
			(layers "F.Cu" "F.Mask" "F.Paste")
			(net "SMB_LM75_2_3V3AUX_SCL_R1")
		)
		(pad "3" smd rect
			(at -2.649982 0.635)
			(size 0.6096 1.3208)
			(layers "F.Cu" "F.Mask" "F.Paste")
			(net "FM_LM75_2_ALERT_N")
		)
		(pad "4" smd rect
			(at -2.649982 1.905)
			(size 0.6096 1.3208)
			(layers "F.Cu" "F.Mask" "F.Paste")
			(net "GND")
		)
		(pad "5" smd rect
			(at 2.649982 1.905)
			(size 0.6096 1.3208)
			(layers "F.Cu" "F.Mask" "F.Paste")
			(net "U272_2_ADD2")
		)
		(pad "6" smd rect
			(at 2.649982 0.635)
			(size 0.6096 1.3208)
			(layers "F.Cu" "F.Mask" "F.Paste")
			(net "U272_2_ADD1")
		)
		(pad "7" smd rect
			(at 2.649982 -0.635)
			(size 0.6096 1.3208)
			(layers "F.Cu" "F.Mask" "F.Paste")
			(net "U272_2_ADD0")
		)
		(pad "8" smd rect
			(at 2.649982 -1.905)
			(size 0.6096 1.3208)
			(layers "F.Cu" "F.Mask" "F.Paste")
			(net "P3V3_AUX")
		)
	)
)
